(kicad_pcb
	(version 20241229)
	(generator "pcbnew")
	(generator_version "9.0")
	(general
		(thickness 1.6296)
		(legacy_teardrops no)
	)
	(paper "A3")
	(title_block
		(title "Thunderbolt to 10GbE adapter")
		(date "2026-04-21")
		(rev "1.1.0")
		(company "Antmicro Ltd")
		(comment 1 "www.antmicro.com")
		(comment 9 "footprints 295-299 of 703")
	)
	(layers
		(0 "F.Cu" signal)
		(4 "In1.Cu" signal)
		(6 "In2.Cu" signal)
		(8 "In3.Cu" signal)
		(10 "In4.Cu" signal)
		(12 "In5.Cu" signal)
		(14 "In6.Cu" signal)
		(2 "B.Cu" signal)
		(9 "F.Adhes" user "F.Adhesive")
		(11 "B.Adhes" user "B.Adhesive")
		(13 "F.Paste" user)
		(15 "B.Paste" user)
		(5 "F.SilkS" user "F.Silkscreen")
		(7 "B.SilkS" user "B.Silkscreen")
		(1 "F.Mask" user)
		(3 "B.Mask" user)
		(17 "Dwgs.User" user "User.Drawings")
		(19 "Cmts.User" user "User.Comments")
		(21 "Eco1.User" user "User.Eco1")
		(23 "Eco2.User" user "User.Eco2")
		(25 "Edge.Cuts" user)
		(27 "Margin" user)
		(31 "F.CrtYd" user "F.Courtyard")
		(29 "B.CrtYd" user "B.Courtyard")
		(35 "F.Fab" user)
		(33 "B.Fab" user)
	)
	(footprint "antmicro-footprints:C_0402_1005Metric"
		(layer "F.Cu")
		(at 145.8 116.4 -90)
		(descr "Capacitor SMD 0402")
		(tags "capacitor SMD 0402")
		(property "Reference" "C103"
			(at 0.4 1.5 270)
			(layer "F.SilkS")
			(effects
				(font
					(size 0.7 0.7)
					(thickness 0.15)
				)
			)
		)
		(property "Value" "C_100n_0402"
			(at -1.022927 2.155213 270)
			(layer "F.Fab")
			(effects
				(font
					(size 0.7 0.7)
					(thickness 0.15)
				)
				(justify left bottom)
			)
		)
		(property "Datasheet" "https://www.murata.com/products/productdetail?partno=GRM155R61H104KE14%23"
			(at 0 0 270)
			(layer "F.Fab")
			(hide yes)
			(effects
				(font
					(size 1.27 1.27)
					(thickness 0.15)
				)
			)
		)
		(property "Description" "SMD Multilayer Ceramic Capacitor, 0.1 µF, 50 V, 0402 [1005 Metric], ± 10%, X5R, GRM Series"
			(at 0 0 270)
			(layer "F.Fab")
			(hide yes)
			(effects
				(font
					(size 1.27 1.27)
					(thickness 0.15)
				)
			)
		)
		(property "MPN" "GRM155R61H104KE14D"
			(at 0 0 270)
			(unlocked yes)
			(layer "F.Fab")
			(hide yes)
			(effects
				(font
					(size 1 1)
					(thickness 0.15)
				)
			)
		)
		(property "Manufacturer" "Murata"
			(at 0 0 270)
			(unlocked yes)
			(layer "F.Fab")
			(hide yes)
			(effects
				(font
					(size 1 1)
					(thickness 0.15)
				)
			)
		)
		(property "License" "Apache-2.0"
			(at 0 0 270)
			(unlocked yes)
			(layer "F.Fab")
			(hide yes)
			(effects
				(font
					(size 1 1)
					(thickness 0.15)
				)
			)
		)
		(property "Val" "100n"
			(at 0 0 270)
			(unlocked yes)
			(layer "F.Fab")
			(hide yes)
			(effects
				(font
					(size 1 1)
					(thickness 0.15)
				)
			)
		)
		(property "Voltage" "50V"
			(at 0 0 270)
			(unlocked yes)
			(layer "F.Fab")
			(hide yes)
			(effects
				(font
					(size 1 1)
					(thickness 0.15)
				)
			)
		)
		(property "Dielectric" "X5R"
			(at 0 0 270)
			(unlocked yes)
			(layer "F.Fab")
			(hide yes)
			(effects
				(font
					(size 1 1)
					(thickness 0.15)
				)
			)
		)
		(property "Author" "Antmicro"
			(at 0 0 270)
			(unlocked yes)
			(layer "F.Fab")
			(hide yes)
			(effects
				(font
					(size 1 1)
					(thickness 0.15)
				)
			)
		)
		(sheetname "/TB flash memory/")
		(sheetfile "flash-memory.kicad_sch")
		(attr smd)
		(fp_rect
			(start -0.925 -0.47)
			(end 0.925 0.47)
			(stroke
				(width 0.05)
				(type default)
			)
			(fill no)
			(layer "F.CrtYd")
		)
		(fp_line
			(start -0.494 0.248)
			(end -0.494 -0.25)
			(stroke
				(width 0.15)
				(type solid)
			)
			(layer "F.Fab")
		)
		(fp_line
			(start 0.504 0.248)
			(end -0.494 0.248)
			(stroke
				(width 0.15)
				(type solid)
			)
			(layer "F.Fab")
		)
		(fp_line
			(start -0.494 -0.25)
			(end 0.504 -0.25)
			(stroke
				(width 0.15)
				(type solid)
			)
			(layer "F.Fab")
		)
		(fp_line
			(start 0.504 -0.25)
			(end 0.504 0.248)
			(stroke
				(width 0.15)
				(type solid)
			)
			(layer "F.Fab")
		)
		(fp_text user "${REFERENCE}"
			(at -0.939 4.599 270)
			(layer "F.Fab")
			(effects
				(font
					(size 0.7 0.7)
					(thickness 0.15)
				)
				(justify left bottom)
			)
		)
		(fp_text user "Author: Antmicro"
			(at -0.939 3.399 270)
			(layer "F.Fab")
			(effects
				(font
					(size 0.7 0.7)
					(thickness 0.15)
				)
				(justify left bottom)
			)
		)
		(fp_text user "License: Apache-2.0"
			(at -0.939 5.799 270)
			(layer "F.Fab")
			(effects
				(font
					(size 0.7 0.7)
					(thickness 0.15)
				)
				(justify left bottom)
			)
		)
		(pad "1" smd roundrect
			(at -0.48 0 270)
			(size 0.59 0.64)
			(layers "F.Cu" "F.Mask" "F.Paste")
			(roundrect_rratio 0.25)
			(net 23 "GND")
			(pintype "passive")
		)
		(pad "2" smd roundrect
			(at 0.48 0 270)
			(size 0.59 0.64)
			(layers "F.Cu" "F.Mask" "F.Paste")
			(roundrect_rratio 0.25)
			(net 57 "+3V3_TB")
			(pintype "passive")
		)
	)
	(footprint "antmicro-footprints:L_Bourns-SRP7028A"
		(layer "F.Cu")
		(at 158.6 56.2 180)
		(property "Reference" "L14"
			(at 6.6 2.4 180)
			(layer "F.SilkS")
			(effects
				(font
					(size 0.7 0.7)
					(thickness 0.15)
				)
				(justify left bottom)
			)
		)
		(property "Value" "L_3u3_6A_Bourns-SRP7028A"
			(at -4.81 4.65 180)
			(layer "F.Fab")
			(effects
				(font
					(size 0.7 0.7)
					(thickness 0.15)
				)
				(justify left bottom)
			)
		)
		(property "Datasheet" "https://www.bourns.com/docs/Product-Datasheets/SRP7028A.pdf"
			(at -0.003 -0.299 180)
			(layer "F.Fab")
			(effects
				(font
					(size 0.7 0.7)
					(thickness 0.15)
				)
				(justify left bottom)
			)
		)
		(property "Description" "Power Inductor (SMD), 3.3 µH, 6 A, 28 mOhm, Shielded, 12 A, SRP7028A Series"
			(at -0.003 -0.299 180)
			(layer "F.Fab")
			(effects
				(font
					(size 0.7 0.7)
					(thickness 0.15)
				)
				(justify left bottom)
			)
		)
		(property "Val" "3u3/6A"
			(at 0 0 180)
			(unlocked yes)
			(layer "F.Fab")
			(hide yes)
			(effects
				(font
					(size 1 1)
					(thickness 0.15)
				)
			)
		)
		(property "Manufacturer" "Bourns"
			(at 0 0 180)
			(unlocked yes)
			(layer "F.Fab")
			(hide yes)
			(effects
				(font
					(size 1 1)
					(thickness 0.15)
				)
			)
		)
		(property "MPN" "SRP7028A-3R3M"
			(at 0 0 180)
			(unlocked yes)
			(layer "F.Fab")
			(hide yes)
			(effects
				(font
					(size 1 1)
					(thickness 0.15)
				)
			)
		)
		(property "ISat" "12 A"
			(at 0 0 180)
			(unlocked yes)
			(layer "F.Fab")
			(hide yes)
			(effects
				(font
					(size 1 1)
					(thickness 0.15)
				)
			)
		)
		(property "IMax" "6 A"
			(at 0 0 180)
			(unlocked yes)
			(layer "F.Fab")
			(hide yes)
			(effects
				(font
					(size 1 1)
					(thickness 0.15)
				)
			)
		)
		(property "Size" "7.3x6.6x2.8"
			(at 0 0 180)
			(unlocked yes)
			(layer "F.Fab")
			(hide yes)
			(effects
				(font
					(size 1 1)
					(thickness 0.15)
				)
			)
		)
		(property "Author" "Antmicro"
			(at 0 0 180)
			(unlocked yes)
			(layer "F.Fab")
			(hide yes)
			(effects
				(font
					(size 1 1)
					(thickness 0.15)
				)
			)
		)
		(property "License" "Apache-2.0"
			(at 0 0 180)
			(unlocked yes)
			(layer "F.Fab")
			(hide yes)
			(effects
				(font
					(size 1 1)
					(thickness 0.15)
				)
			)
		)
		(sheetname "/Power input/")
		(sheetfile "power_input.kicad_sch")
		(attr smd)
		(fp_line
			(start 3.44 2.115)
			(end 3.44 3.39)
			(stroke
				(width 0.15)
				(type solid)
			)
			(layer "F.SilkS")
		)
		(fp_line
			(start 3.44 -2.115)
			(end 3.44 -3.39)
			(stroke
				(width 0.15)
				(type solid)
			)
			(layer "F.SilkS")
		)
		(fp_line
			(start 3.44 -3.39)
			(end -3.44 -3.39)
			(stroke
				(width 0.15)
				(type solid)
			)
			(layer "F.SilkS")
		)
		(fp_line
			(start -3.44 3.39)
			(end 3.44 3.39)
			(stroke
				(width 0.15)
				(type solid)
			)
			(layer "F.SilkS")
		)
		(fp_line
			(start -3.44 2.115)
			(end -3.44 3.39)
			(stroke
				(width 0.15)
				(type solid)
			)
			(layer "F.SilkS")
		)
		(fp_line
			(start -3.44 -2.115)
			(end -3.44 -3.39)
			(stroke
				(width 0.15)
				(type solid)
			)
			(layer "F.SilkS")
		)
		(fp_circle
			(center -4.39 0)
			(end -4.34 0)
			(stroke
				(width 0.15)
				(type solid)
			)
			(fill yes)
			(layer "F.SilkS")
		)
		(fp_rect
			(start -4.5 -3.6)
			(end 4.5 3.6)
			(stroke
				(width 0.05)
				(type solid)
			)
			(fill no)
			(layer "F.CrtYd")
		)
		(fp_text user "License: Apache-2.0"
			(at -4.81 8.25 180)
			(layer "F.Fab")
			(effects
				(font
					(size 0.7 0.7)
					(thickness 0.15)
				)
				(justify left bottom)
			)
		)
		(fp_text user "Author: Antmicro"
			(at -4.81 5.85 180)
			(layer "F.Fab")
			(effects
				(font
					(size 0.7 0.7)
					(thickness 0.15)
				)
				(justify left bottom)
			)
		)
		(fp_text user "${REFERENCE}"
			(at -4.81 7.05 180)
			(layer "F.Fab")
			(effects
				(font
					(size 0.7 0.7)
					(thickness 0.15)
				)
				(justify left bottom)
			)
		)
		(pad "1" smd roundrect
			(at -2.725 0 180)
			(size 2.95 3.5)
			(layers "F.Cu" "F.Mask" "F.Paste")
			(roundrect_rratio 0.05)
			(net 354 "/Power input/5V_SW")
			(pintype "passive")
		)
		(pad "2" smd roundrect
			(at 2.725 0 180)
			(size 2.95 3.5)
			(layers "F.Cu" "F.Mask" "F.Paste")
			(roundrect_rratio 0.05)
			(net 349 "/Power input/5V_OUT")
			(pintype "passive")
		)
	)
	(footprint "antmicro-footprints:C_0402_1005Metric"
		(layer "F.Cu")
		(at 117 73.9)
		(descr "Capacitor SMD 0402")
		(tags "capacitor SMD 0402")
		(property "Reference" "C308"
			(at 3.6 -10.5 0)
			(layer "F.SilkS")
			(effects
				(font
					(size 0.7 0.7)
					(thickness 0.15)
				)
				(justify left bottom)
			)
		)
		(property "Value" "C_1u_0402"
			(at -1.022927 2.155213 0)
			(layer "F.Fab")
			(effects
				(font
					(size 0.7 0.7)
					(thickness 0.15)
				)
				(justify left bottom)
			)
		)
		(property "Datasheet" "https://product.tdk.com/en/search/capacitor/ceramic/mlcc/info?part_no=C1005X6S1A105K050BC"
			(at 0 0 0)
			(layer "F.Fab")
			(hide yes)
			(effects
				(font
					(size 1.27 1.27)
					(thickness 0.15)
				)
			)
		)
		(property "Description" "SMD Multilayer Ceramic Capacitor, 1 µF, 10 V, 0402 [1005 Metric], ± 10%, X6S, C"
			(at 0 0 0)
			(layer "F.Fab")
			(hide yes)
			(effects
				(font
					(size 1.27 1.27)
					(thickness 0.15)
				)
			)
		)
		(property "MPN" "C1005X6S1A105K050BC"
			(at 0 0 0)
			(unlocked yes)
			(layer "F.Fab")
			(hide yes)
			(effects
				(font
					(size 1 1)
					(thickness 0.15)
				)
			)
		)
		(property "Manufacturer" "TDK"
			(at 0 0 0)
			(unlocked yes)
			(layer "F.Fab")
			(hide yes)
			(effects
				(font
					(size 1 1)
					(thickness 0.15)
				)
			)
		)
		(property "License" "Apache-2.0"
			(at 0 0 0)
			(unlocked yes)
			(layer "F.Fab")
			(hide yes)
			(effects
				(font
					(size 1 1)
					(thickness 0.15)
				)
			)
		)
		(property "Author" "Antmicro"
			(at 0 0 0)
			(unlocked yes)
			(layer "F.Fab")
			(hide yes)
			(effects
				(font
					(size 1 1)
					(thickness 0.15)
				)
			)
		)
		(property "Val" "1u"
			(at 0 0 0)
			(unlocked yes)
			(layer "F.Fab")
			(hide yes)
			(effects
				(font
					(size 1 1)
					(thickness 0.15)
				)
			)
		)
		(property "Voltage" ""
			(at 0 0 0)
			(unlocked yes)
			(layer "F.Fab")
			(hide yes)
			(effects
				(font
					(size 1 1)
					(thickness 0.15)
				)
			)
		)
		(property "Dielectric" ""
			(at 0 0 0)
			(unlocked yes)
			(layer "F.Fab")
			(hide yes)
			(effects
				(font
					(size 1 1)
					(thickness 0.15)
				)
			)
		)
		(sheetname "/Fan controller/")
		(sheetfile "fan-controller.kicad_sch")
		(attr smd)
		(fp_rect
			(start -0.925 -0.47)
			(end 0.925 0.47)
			(stroke
				(width 0.05)
				(type default)
			)
			(fill no)
			(layer "F.CrtYd")
		)
		(fp_line
			(start -0.494 -0.25)
			(end 0.504 -0.25)
			(stroke
				(width 0.15)
				(type solid)
			)
			(layer "F.Fab")
		)
		(fp_line
			(start -0.494 0.248)
			(end -0.494 -0.25)
			(stroke
				(width 0.15)
				(type solid)
			)
			(layer "F.Fab")
		)
		(fp_line
			(start 0.504 -0.25)
			(end 0.504 0.248)
			(stroke
				(width 0.15)
				(type solid)
			)
			(layer "F.Fab")
		)
		(fp_line
			(start 0.504 0.248)
			(end -0.494 0.248)
			(stroke
				(width 0.15)
				(type solid)
			)
			(layer "F.Fab")
		)
		(fp_text user "License: Apache-2.0"
			(at -0.939 5.799 0)
			(layer "F.Fab")
			(effects
				(font
					(size 0.7 0.7)
					(thickness 0.15)
				)
				(justify left bottom)
			)
		)
		(fp_text user "${REFERENCE}"
			(at -0.939 4.599 0)
			(layer "F.Fab")
			(effects
				(font
					(size 0.7 0.7)
					(thickness 0.15)
				)
				(justify left bottom)
			)
		)
		(fp_text user "Author: Antmicro"
			(at -0.939 3.399 0)
			(layer "F.Fab")
			(effects
				(font
					(size 0.7 0.7)
					(thickness 0.15)
				)
				(justify left bottom)
			)
		)
		(pad "1" smd roundrect
			(at -0.48 0)
			(size 0.59 0.64)
			(layers "F.Cu" "F.Mask" "F.Paste")
			(roundrect_rratio 0.25)
			(net 23 "GND")
			(pintype "passive")
		)
		(pad "2" smd roundrect
			(at 0.48 0)
			(size 0.59 0.64)
			(layers "F.Cu" "F.Mask" "F.Paste")
			(roundrect_rratio 0.25)
			(net 151 "/Fan controller/SENSE")
			(pintype "passive")
		)
	)
	(footprint "antmicro-footprints:C_0402_1005Metric"
		(layer "F.Cu")
		(at 165.265 62 90)
		(descr "Capacitor SMD 0402")
		(tags "capacitor SMD 0402")
		(property "Reference" "C282"
			(at 5.8 -0.065 90)
			(layer "F.SilkS")
			(effects
				(font
					(size 0.7 0.7)
					(thickness 0.15)
				)
				(justify left bottom)
			)
		)
		(property "Value" "C_100n_0402"
			(at -1.022927 2.155213 90)
			(layer "F.Fab")
			(effects
				(font
					(size 0.7 0.7)
					(thickness 0.15)
				)
				(justify left bottom)
			)
		)
		(property "Datasheet" "https://www.murata.com/products/productdetail?partno=GRM155R61H104KE14%23"
			(at 0 0 90)
			(layer "F.Fab")
			(hide yes)
			(effects
				(font
					(size 1.27 1.27)
					(thickness 0.15)
				)
			)
		)
		(property "Description" "SMD Multilayer Ceramic Capacitor, 0.1 µF, 50 V, 0402 [1005 Metric], ± 10%, X5R, GRM Series"
			(at 0 0 90)
			(layer "F.Fab")
			(hide yes)
			(effects
				(font
					(size 1.27 1.27)
					(thickness 0.15)
				)
			)
		)
		(property "MPN" "GRM155R61H104KE14D"
			(at 0 0 90)
			(unlocked yes)
			(layer "F.Fab")
			(hide yes)
			(effects
				(font
					(size 1 1)
					(thickness 0.15)
				)
			)
		)
		(property "Val" "100n"
			(at 0 0 90)
			(unlocked yes)
			(layer "F.Fab")
			(hide yes)
			(effects
				(font
					(size 1 1)
					(thickness 0.15)
				)
			)
		)
		(property "Voltage" "50V"
			(at 0 0 90)
			(unlocked yes)
			(layer "F.Fab")
			(hide yes)
			(effects
				(font
					(size 1 1)
					(thickness 0.15)
				)
			)
		)
		(property "Dielectric" "X5R"
			(at 0 0 90)
			(unlocked yes)
			(layer "F.Fab")
			(hide yes)
			(effects
				(font
					(size 1 1)
					(thickness 0.15)
				)
			)
		)
		(property "Manufacturer" "Murata"
			(at 0 0 90)
			(unlocked yes)
			(layer "F.Fab")
			(hide yes)
			(effects
				(font
					(size 1 1)
					(thickness 0.15)
				)
			)
		)
		(property "License" "Apache-2.0"
			(at 0 0 90)
			(unlocked yes)
			(layer "F.Fab")
			(hide yes)
			(effects
				(font
					(size 1 1)
					(thickness 0.15)
				)
			)
		)
		(property "Author" "Antmicro"
			(at 0 0 90)
			(unlocked yes)
			(layer "F.Fab")
			(hide yes)
			(effects
				(font
					(size 1 1)
					(thickness 0.15)
				)
			)
		)
		(sheetname "/X710-AT2 10GbE/")
		(sheetfile "x710-at2-10gbe.kicad_sch")
		(attr smd)
		(fp_rect
			(start -0.925 -0.47)
			(end 0.925 0.47)
			(stroke
				(width 0.05)
				(type default)
			)
			(fill no)
			(layer "F.CrtYd")
		)
		(fp_line
			(start 0.504 -0.25)
			(end 0.504 0.248)
			(stroke
				(width 0.15)
				(type solid)
			)
			(layer "F.Fab")
		)
		(fp_line
			(start -0.494 -0.25)
			(end 0.504 -0.25)
			(stroke
				(width 0.15)
				(type solid)
			)
			(layer "F.Fab")
		)
		(fp_line
			(start 0.504 0.248)
			(end -0.494 0.248)
			(stroke
				(width 0.15)
				(type solid)
			)
			(layer "F.Fab")
		)
		(fp_line
			(start -0.494 0.248)
			(end -0.494 -0.25)
			(stroke
				(width 0.15)
				(type solid)
			)
			(layer "F.Fab")
		)
		(fp_text user "License: Apache-2.0"
			(at -0.939 5.799 90)
			(layer "F.Fab")
			(effects
				(font
					(size 0.7 0.7)
					(thickness 0.15)
				)
				(justify left bottom)
			)
		)
		(fp_text user "${REFERENCE}"
			(at -0.939 4.599 90)
			(layer "F.Fab")
			(effects
				(font
					(size 0.7 0.7)
					(thickness 0.15)
				)
				(justify left bottom)
			)
		)
		(fp_text user "Author: Antmicro"
			(at -0.939 3.399 90)
			(layer "F.Fab")
			(effects
				(font
					(size 0.7 0.7)
					(thickness 0.15)
				)
				(justify left bottom)
			)
		)
		(pad "1" smd roundrect
			(at -0.48 0 90)
			(size 0.59 0.64)
			(layers "F.Cu" "F.Mask" "F.Paste")
			(roundrect_rratio 0.25)
			(net 23 "GND")
			(pintype "passive")
		)
		(pad "2" smd roundrect
			(at 0.48 0 90)
			(size 0.59 0.64)
			(layers "F.Cu" "F.Mask" "F.Paste")
			(roundrect_rratio 0.25)
			(net 7 "+3V3")
			(pintype "passive")
		)
	)
	(footprint "antmicro-footprints:R_0402_1005Metric"
		(layer "F.Cu")
		(at 124 72)
		(descr "Resistor SMD 0402")
		(tags "resistor SMD 0402")
		(property "Reference" "R220"
			(at 1 -0.3 0)
			(layer "F.SilkS")
			(effects
				(font
					(size 0.7 0.7)
					(thickness 0.15)
				)
				(justify left bottom)
			)
		)
		(property "Value" "R_0R_0402"
			(at -1.011843 1.772047 0)
			(layer "F.Fab")
			(effects
				(font
					(size 0.7 0.7)
					(thickness 0.15)
				)
				(justify left bottom)
			)
		)
		(property "Datasheet" "https://industrial.panasonic.com/cdbs/www-data/pdf/RDA0000/AOA0000C301.pdf"
			(at 0 0 0)
			(layer "F.Fab")
			(hide yes)
			(effects
				(font
					(size 1.27 1.27)
					(thickness 0.15)
				)
			)
		)
		(property "Description" "SMD Chip Resistor, Jumper, 0 ohm, 100 mW, 0402 [1005 Metric], Thick Film, General Purpose"
			(at 0 0 0)
			(layer "F.Fab")
			(hide yes)
			(effects
				(font
					(size 1.27 1.27)
					(thickness 0.15)
				)
			)
		)
		(property "MPN" "ERJ2GE0R00X"
			(at 0 0 0)
			(unlocked yes)
			(layer "F.Fab")
			(hide yes)
			(effects
				(font
					(size 1 1)
					(thickness 0.15)
				)
			)
		)
		(property "Manufacturer" "Panasonic"
			(at 0 0 0)
			(unlocked yes)
			(layer "F.Fab")
			(hide yes)
			(effects
				(font
					(size 1 1)
					(thickness 0.15)
				)
			)
		)
		(property "License" "Apache-2.0"
			(at 0 0 0)
			(unlocked yes)
			(layer "F.Fab")
			(hide yes)
			(effects
				(font
					(size 1 1)
					(thickness 0.15)
				)
			)
		)
		(property "Author" "Antmicro"
			(at 0 0 0)
			(unlocked yes)
			(layer "F.Fab")
			(hide yes)
			(effects
				(font
					(size 1 1)
					(thickness 0.15)
				)
			)
		)
		(property "Val" "0R"
			(at 0 0 0)
			(unlocked yes)
			(layer "F.Fab")
			(hide yes)
			(effects
				(font
					(size 1 1)
					(thickness 0.15)
				)
			)
		)
		(property "Tolerance" "~"
			(at 0 0 0)
			(unlocked yes)
			(layer "F.Fab")
			(hide yes)
			(effects
				(font
					(size 1 1)
					(thickness 0.15)
				)
			)
		)
		(property "Current" "1A"
			(at 0 0 0)
			(unlocked yes)
			(layer "F.Fab")
			(hide yes)
			(effects
				(font
					(size 1 1)
					(thickness 0.15)
				)
			)
		)
		(sheetname "/Fan controller/")
		(sheetfile "fan-controller.kicad_sch")
		(attr smd dnp)
		(fp_rect
			(start -0.925 -0.47)
			(end 0.925 0.47)
			(stroke
				(width 0.05)
				(type default)
			)
			(fill no)
			(layer "F.CrtYd")
		)
		(fp_rect
			(start -0.5 -0.25)
			(end 0.5 0.25)
			(stroke
				(width 0.15)
				(type solid)
			)
			(fill no)
			(layer "F.Fab")
		)
		(fp_text user "${REFERENCE}"
			(at -0.95 3.168 0)
			(layer "F.Fab")
			(effects
				(font
					(size 0.7 0.7)
					(thickness 0.15)
				)
				(justify left bottom)
			)
		)
		(fp_text user "Author: Antmicro"
			(at -0.95 4.169 0)
			(layer "F.Fab")
			(effects
				(font
					(size 0.7 0.7)
					(thickness 0.15)
				)
				(justify left bottom)
			)
		)
		(fp_text user "License: Apache-2.0"
			(at -0.95 5.169 0)
			(layer "F.Fab")
			(effects
				(font
					(size 0.7 0.7)
					(thickness 0.15)
				)
				(justify left bottom)
			)
		)
		(pad "1" smd roundrect
			(at -0.48 0)
			(size 0.59 0.64)
			(layers "F.Cu" "F.Mask" "F.Paste")
			(roundrect_rratio 0.25)
			(net 156 "/Fan controller/D0")
			(pintype "passive")
		)
		(pad "2" smd roundrect
			(at 0.48 0)
			(size 0.59 0.64)
			(layers "F.Cu" "F.Mask" "F.Paste")
			(roundrect_rratio 0.25)
			(net 40 "+5V")
			(pintype "passive")
		)
	)
)
